# T6G (Grand Teton) — schematic netlist excerpt (pin names and nets, part order shuffled) for the footprints in the layout excerpt that follows; sources: Cadence DE-HDL packaged netlist, KiCad conversion of 04192023_DAF0TMB3IC0_F0TG_MB_C_brd_V02_OCP.brd

R8165  Q_RES  1K 1% CHIP  pkg 0402LF  page 210 : A = P3V3_AUX ; B = PWRGD_PVDDCR_SOC_P1_R

U204  74LVC1G126SE7  74LVC1G126SE-7 IC  pkg SOT353_0-65_2X1-25  page 130
  OE  = FM_UART_EN
  A  = UART_BMC_BIC_R_RX
  GND  = GND
  Y  = UART_BMC_BIC_R_BUF_RX
  VCC  = P3V3_AUX

(kicad_pcb
	(version 20260206)
	(generator "pcbnew")
	(generator_version "10.0")
	(general
		(thickness 1.6)
		(legacy_teardrops no)
	)
	(paper "A4")
	(title_block
		(title "04192023_DAF0TMB3IC0_F0TG_MB_C_brd_V02_OCP.brd")
		(comment 1 "Grand Teton / footprints 3395-3396 of 8354")
	)
	(layers
		(0 "F.Cu" signal "TOP")
		(4 "In1.Cu" signal "GND")
		(6 "In2.Cu" signal "IN1")
		(8 "In3.Cu" signal "GND1")
		(10 "In4.Cu" signal "IN2")
		(12 "In5.Cu" signal "GND2")
		(14 "In6.Cu" signal "IN3")
		(16 "In7.Cu" signal "GND3")
		(18 "In8.Cu" signal "VCC")
		(20 "In9.Cu" signal "VCC1")
		(22 "In10.Cu" signal "GND4")
		(24 "In11.Cu" signal "IN4")
		(26 "In12.Cu" signal "GND5")
		(28 "In13.Cu" signal "IN5")
		(30 "In14.Cu" signal "GND6")
		(32 "In15.Cu" signal "IN6")
		(34 "In16.Cu" signal "GND7")
		(2 "B.Cu" signal "BOTTOM")
		(9 "F.Adhes" user "F.Adhesive")
		(11 "B.Adhes" user "B.Adhesive")
		(13 "F.Paste" user "Package Geometry/Pastemask Top")
		(15 "B.Paste" user "Package Geometry/Pastemask Bottom")
		(5 "F.SilkS" user "Ref Des/Silkscreen Top")
		(7 "B.SilkS" user "Ref Des/Silkscreen Bottom")
		(1 "F.Mask" user "Board Geometry/Soldermask Top")
		(3 "B.Mask" user "Board Geometry/Soldermask Bottom")
		(17 "Dwgs.User" user "User.Drawings")
		(19 "Cmts.User" user "User.Comments")
		(21 "Eco1.User" user "User.Eco1")
		(23 "Eco2.User" user "User.Eco2")
		(25 "Edge.Cuts" user "Board Geometry/Outline")
		(27 "Margin" user)
		(31 "F.CrtYd" user "Package Geometry/Place Bound Top")
		(29 "B.CrtYd" user "Package Geometry/Place Bound Bottom")
		(35 "F.Fab" user "Ref Des/Assembly Top")
		(33 "B.Fab" user "Ref Des/Assembly Bottom")
	)
	(footprint ""
		(layer "F.Cu")
		(at 90.209878 -144.88541)
		(property "Reference" "R8165"
			(at 0 0 0)
			(layer "F.SilkS")
			(hide yes)
			(effects
				(font
					(size 1.27 1.27)
				)
			)
		)
		(property "Value" ""
			(at 0 0 0)
			(layer "F.Fab")
			(effects
				(font
					(size 1.27 1.27)
				)
			)
		)
		(duplicate_pad_numbers_are_jumpers no)
		(fp_line
			(start -0.7874 -0.4064)
			(end 0.7874 -0.4064)
			(stroke
				(width 0.1524)
				(type default)
			)
			(layer "F.SilkS")
		)
		(fp_line
			(start -0.7874 0.4064)
			(end -0.7874 -0.4064)
			(stroke
				(width 0.1524)
				(type default)
			)
			(layer "F.SilkS")
		)
		(fp_line
			(start 0.7874 -0.4064)
			(end 0.7874 0.4064)
			(stroke
				(width 0.1524)
				(type default)
			)
			(layer "F.SilkS")
		)
		(fp_line
			(start 0.7874 0.4064)
			(end -0.7874 0.4064)
			(stroke
				(width 0.1524)
				(type default)
			)
			(layer "F.SilkS")
		)
		(fp_line
			(start -0.67945 -0.305054)
			(end -0.12065 -0.305054)
			(stroke
				(width 0.1)
				(type default)
			)
			(layer "F.Fab")
		)
		(fp_line
			(start -0.67945 0.3048)
			(end -0.67945 -0.305054)
			(stroke
				(width 0.1)
				(type default)
			)
			(layer "F.Fab")
		)
		(fp_line
			(start -0.12065 -0.305054)
			(end -0.12065 -0.2794)
			(stroke
				(width 0.1)
				(type default)
			)
			(layer "F.Fab")
		)
		(fp_line
			(start -0.12065 -0.2794)
			(end 0.12065 -0.2794)
			(stroke
				(width 0.1)
				(type default)
			)
			(layer "F.Fab")
		)
		(fp_line
			(start -0.12065 0.2794)
			(end -0.12065 0.3048)
			(stroke
				(width 0.1)
				(type default)
			)
			(layer "F.Fab")
		)
		(fp_line
			(start -0.12065 0.3048)
			(end -0.67945 0.3048)
			(stroke
				(width 0.1)
				(type default)
			)
			(layer "F.Fab")
		)
		(fp_line
			(start 0.120396 0.2794)
			(end -0.12065 0.2794)
			(stroke
				(width 0.1)
				(type default)
			)
			(layer "F.Fab")
		)
		(fp_line
			(start 0.120396 0.3048)
			(end 0.120396 0.2794)
			(stroke
				(width 0.1)
				(type default)
			)
			(layer "F.Fab")
		)
		(fp_line
			(start 0.12065 -0.3048)
			(end 0.67945 -0.3048)
			(stroke
				(width 0.1)
				(type default)
			)
			(layer "F.Fab")
		)
		(fp_line
			(start 0.12065 -0.2794)
			(end 0.12065 -0.3048)
			(stroke
				(width 0.1)
				(type default)
			)
			(layer "F.Fab")
		)
		(fp_line
			(start 0.67945 -0.3048)
			(end 0.67945 0.3048)
			(stroke
				(width 0.1)
				(type default)
			)
			(layer "F.Fab")
		)
		(fp_line
			(start 0.67945 0.3048)
			(end 0.120396 0.3048)
			(stroke
				(width 0.1)
				(type default)
			)
			(layer "F.Fab")
		)
		(pad "1" smd circle
			(at -0.40005 0)
			(size 0 0)
			(layers "F.Cu" "F.Mask" "F.Paste")
			(net "P3V3_AUX")
		)
		(pad "2" smd circle
			(at 0.40005 0)
			(size 0 0)
			(layers "F.Cu" "F.Mask" "F.Paste")
			(net "PWRGD_PVDDCR_SOC_P1_R")
		)
	)
	(footprint ""
		(layer "F.Cu")
		(at 359.709974 -413.859218 90)
		(property "Reference" "U204"
			(at 0.003048 -1.732534 90)
			(unlocked yes)
			(layer "F.SilkS")
			(effects
				(font
					(size 0.7874 0.5842)
					(thickness 0.1524)
				)
				(justify left)
			)
		)
		(property "Value" ""
			(at 0 0 90)
			(layer "F.Fab")
			(effects
				(font
					(size 1.27 1.27)
				)
			)
		)
		(duplicate_pad_numbers_are_jumpers no)
		(fp_line
			(start 1.400048 -1.100074)
			(end -1.400048 -1.100074)
			(stroke
				(width 0.1524)
				(type default)
			)
			(layer "F.SilkS")
		)
		(fp_line
			(start 1.400048 -1.100074)
			(end 1.400048 1.100074)
			(stroke
				(width 0.1524)
				(type default)
			)
			(layer "F.SilkS")
		)
		(fp_line
			(start 1.400048 1.100074)
			(end -1.400048 1.100074)
			(stroke
				(width 0.1524)
				(type default)
			)
			(layer "F.SilkS")
		)
		(fp_line
			(start -1.400048 1.100074)
			(end -1.400048 -1.100074)
			(stroke
				(width 0.1524)
				(type default)
			)
			(layer "F.SilkS")
		)
		(fp_poly
			(pts
				(xy -2.606548 -0.141986) (xy -2.606548 -1.157986) (xy -1.590548 -0.649986)
			)
			(stroke
				(width 0)
				(type default)
			)
			(fill yes)
			(layer "F.SilkS")
		)
		(fp_line
			(start 0.674878 -1.100074)
			(end 0.674878 1.100074)
			(stroke
				(width 0.1)
				(type default)
			)
			(layer "F.Fab")
		)
		(fp_line
			(start -0.674878 -1.100074)
			(end 0.674878 -1.100074)
			(stroke
				(width 0.1)
				(type default)
			)
			(layer "F.Fab")
		)
		(fp_line
			(start 0.674878 1.100074)
			(end -0.674878 1.100074)
			(stroke
				(width 0.1)
				(type default)
			)
			(layer "F.Fab")
		)
		(fp_line
			(start -0.674878 1.100074)
			(end -0.674878 -1.100074)
			(stroke
				(width 0.1)
				(type default)
			)
			(layer "F.Fab")
		)
		(fp_poly
			(pts
				(xy -1.590548 -0.649986) (xy -2.606548 -1.157986) (xy -2.606548 -0.141986)
			)
			(stroke
				(width 0)
				(type default)
			)
			(fill yes)
			(layer "F.Fab")
		)
		(pad "1" smd rect
			(at -0.94996 -0.649986)
			(size 0.4318 0.6096)
			(layers "F.Cu" "F.Mask" "F.Paste")
			(net "FM_UART_EN")
		)
		(pad "2" smd rect
			(at -0.94996 0)
			(size 0.4318 0.6096)
			(layers "F.Cu" "F.Mask" "F.Paste")
			(net "UART_BMC_BIC_R_RX")
		)
		(pad "3" smd rect
			(at -0.94996 0.649986)
			(size 0.4318 0.6096)
			(layers "F.Cu" "F.Mask" "F.Paste")
			(net "GND")
		)
		(pad "4" smd rect
			(at 0.94996 0.649986)
			(size 0.4318 0.6096)
			(layers "F.Cu" "F.Mask" "F.Paste")
			(net "UART_BMC_BIC_R_BUF_RX")
		)
		(pad "5" smd rect
			(at 0.94996 -0.649986)
			(size 0.4318 0.6096)
			(layers "F.Cu" "F.Mask" "F.Paste")
			(net "P3V3_AUX")
		)
	)
)
